(kicad_pcb
	(version 20260206)
	(generator "pcbnew")
	(generator_version "10.0")
	(general
		(thickness 1.6)
		(legacy_teardrops no)
	)
	(paper "A4")
	(title_block
		(title "03242023_DA0F0TMBIJ0_F0T_Motherboard_J_brd_V01_OCP.brd")
		(comment 1 "Grand Teton / footprints 120-125 of 6105")
	)
	(layers
		(0 "F.Cu" signal "TOP")
		(4 "In1.Cu" signal "GND")
		(6 "In2.Cu" signal "IN1")
		(8 "In3.Cu" signal "GND1")
		(10 "In4.Cu" signal "IN2")
		(12 "In5.Cu" signal "GND2")
		(14 "In6.Cu" signal "IN3")
		(16 "In7.Cu" signal "GND3")
		(18 "In8.Cu" signal "VCC")
		(20 "In9.Cu" signal "VCC1")
		(22 "In10.Cu" signal "GND4")
		(24 "In11.Cu" signal "IN4")
		(26 "In12.Cu" signal "GND5")
		(28 "In13.Cu" signal "IN5")
		(30 "In14.Cu" signal "GND6")
		(32 "In15.Cu" signal "IN6")
		(34 "In16.Cu" signal "GND7")
		(2 "B.Cu" signal "BOTTOM")
		(9 "F.Adhes" user "F.Adhesive")
		(11 "B.Adhes" user "B.Adhesive")
		(13 "F.Paste" user "Package Geometry/Pastemask Top")
		(15 "B.Paste" user "Package Geometry/Pastemask Bottom")
		(5 "F.SilkS" user "Ref Des/Silkscreen Top")
		(7 "B.SilkS" user "Ref Des/Silkscreen Bottom")
		(1 "F.Mask" user "Board Geometry/Soldermask Top")
		(3 "B.Mask" user "Board Geometry/Soldermask Bottom")
		(17 "Dwgs.User" user "User.Drawings")
		(19 "Cmts.User" user "User.Comments")
		(21 "Eco1.User" user "User.Eco1")
		(23 "Eco2.User" user "User.Eco2")
		(25 "Edge.Cuts" user "Board Geometry/Outline")
		(27 "Margin" user)
		(31 "F.CrtYd" user "Package Geometry/Place Bound Top")
		(29 "B.CrtYd" user "Package Geometry/Place Bound Bottom")
		(35 "F.Fab" user "Ref Des/Assembly Top")
		(33 "B.Fab" user "Ref Des/Assembly Bottom")
	)
	(footprint ""
		(layer "F.Cu")
		(at 149.368256 -64.059308)
		(property "Reference" "R2457"
			(at 0 0 0)
			(layer "F.SilkS")
			(hide yes)
			(effects
				(font
					(size 1.27 1.27)
				)
			)
		)
		(property "Value" ""
			(at 0 0 0)
			(layer "F.Fab")
			(effects
				(font
					(size 1.27 1.27)
				)
			)
		)
		(duplicate_pad_numbers_are_jumpers no)
		(fp_line
			(start -0.7874 -0.4064)
			(end 0.7874 -0.4064)
			(stroke
				(width 0.1524)
				(type default)
			)
			(layer "F.SilkS")
		)
		(fp_line
			(start -0.7874 0.4064)
			(end -0.7874 -0.4064)
			(stroke
				(width 0.1524)
				(type default)
			)
			(layer "F.SilkS")
		)
		(fp_line
			(start 0.7874 -0.4064)
			(end 0.7874 0.4064)
			(stroke
				(width 0.1524)
				(type default)
			)
			(layer "F.SilkS")
		)
		(fp_line
			(start 0.7874 0.4064)
			(end -0.7874 0.4064)
			(stroke
				(width 0.1524)
				(type default)
			)
			(layer "F.SilkS")
		)
		(fp_line
			(start -0.67945 -0.305054)
			(end -0.12065 -0.305054)
			(stroke
				(width 0.1)
				(type default)
			)
			(layer "F.Fab")
		)
		(fp_line
			(start -0.67945 0.3048)
			(end -0.67945 -0.305054)
			(stroke
				(width 0.1)
				(type default)
			)
			(layer "F.Fab")
		)
		(fp_line
			(start -0.12065 -0.305054)
			(end -0.12065 -0.2794)
			(stroke
				(width 0.1)
				(type default)
			)
			(layer "F.Fab")
		)
		(fp_line
			(start -0.12065 -0.2794)
			(end 0.12065 -0.2794)
			(stroke
				(width 0.1)
				(type default)
			)
			(layer "F.Fab")
		)
		(fp_line
			(start -0.12065 0.2794)
			(end -0.12065 0.3048)
			(stroke
				(width 0.1)
				(type default)
			)
			(layer "F.Fab")
		)
		(fp_line
			(start -0.12065 0.3048)
			(end -0.67945 0.3048)
			(stroke
				(width 0.1)
				(type default)
			)
			(layer "F.Fab")
		)
		(fp_line
			(start 0.120396 0.2794)
			(end -0.12065 0.2794)
			(stroke
				(width 0.1)
				(type default)
			)
			(layer "F.Fab")
		)
		(fp_line
			(start 0.120396 0.3048)
			(end 0.120396 0.2794)
			(stroke
				(width 0.1)
				(type default)
			)
			(layer "F.Fab")
		)
		(fp_line
			(start 0.12065 -0.3048)
			(end 0.67945 -0.3048)
			(stroke
				(width 0.1)
				(type default)
			)
			(layer "F.Fab")
		)
		(fp_line
			(start 0.12065 -0.2794)
			(end 0.12065 -0.3048)
			(stroke
				(width 0.1)
				(type default)
			)
			(layer "F.Fab")
		)
		(fp_line
			(start 0.67945 -0.3048)
			(end 0.67945 0.3048)
			(stroke
				(width 0.1)
				(type default)
			)
			(layer "F.Fab")
		)
		(fp_line
			(start 0.67945 0.3048)
			(end 0.120396 0.3048)
			(stroke
				(width 0.1)
				(type default)
			)
			(layer "F.Fab")
		)
		(pad "1" smd circle
			(at -0.40005 0)
			(size 0 0)
			(layers "F.Cu" "F.Mask" "F.Paste")
			(net "E1S_0_EN")
		)
		(pad "2" smd circle
			(at 0.40005 0)
			(size 0 0)
			(layers "F.Cu" "F.Mask" "F.Paste")
			(net "GND")
		)
	)
	(footprint ""
		(layer "F.Cu")
		(at 431.062638 -368.79149)
		(property "Reference" "PC1673"
			(at 0 0 0)
			(layer "F.SilkS")
			(hide yes)
			(effects
				(font
					(size 1.27 1.27)
				)
			)
		)
		(property "Value" ""
			(at 0 0 0)
			(layer "F.Fab")
			(effects
				(font
					(size 1.27 1.27)
				)
			)
		)
		(duplicate_pad_numbers_are_jumpers no)
		(fp_line
			(start -1.524 -0.762)
			(end 1.524 -0.762)
			(stroke
				(width 0.1524)
				(type default)
			)
			(layer "F.SilkS")
		)
		(fp_line
			(start -1.524 0.762)
			(end -1.524 -0.762)
			(stroke
				(width 0.1524)
				(type default)
			)
			(layer "F.SilkS")
		)
		(fp_line
			(start 1.524 -0.762)
			(end 1.524 0.762)
			(stroke
				(width 0.1524)
				(type default)
			)
			(layer "F.SilkS")
		)
		(fp_line
			(start 1.524 0.762)
			(end -1.524 0.762)
			(stroke
				(width 0.1524)
				(type default)
			)
			(layer "F.SilkS")
		)
		(fp_line
			(start -1.1049 -0.724916)
			(end -1.1049 0.724916)
			(stroke
				(width 0.1)
				(type default)
			)
			(layer "F.Fab")
		)
		(fp_line
			(start -1.1049 0.724916)
			(end 1.1049 0.724916)
			(stroke
				(width 0.1)
				(type default)
			)
			(layer "F.Fab")
		)
		(fp_line
			(start 1.1049 -0.724916)
			(end -1.1049 -0.724916)
			(stroke
				(width 0.1)
				(type default)
			)
			(layer "F.Fab")
		)
		(fp_line
			(start 1.1049 0.724916)
			(end 1.1049 -0.724916)
			(stroke
				(width 0.1)
				(type default)
			)
			(layer "F.Fab")
		)
		(pad "1" smd rect
			(at -0.889 0 180)
			(size 1.016 1.27)
			(layers "F.Cu" "F.Mask" "F.Paste")
			(net "SW_P12V_PVCCFA_EHV_FIVRA_CPU0_R")
		)
		(pad "2" smd rect
			(at 0.889 0 180)
			(size 1.016 1.27)
			(layers "F.Cu" "F.Mask" "F.Paste")
			(net "GND")
		)
	)
	(footprint ""
		(layer "F.Cu")
		(at 39.827454 -112.603026 180)
		(property "Reference" "R3680"
			(at 0 0 180)
			(layer "F.SilkS")
			(hide yes)
			(effects
				(font
					(size 1.27 1.27)
				)
			)
		)
		(property "Value" ""
			(at 0 0 180)
			(layer "F.Fab")
			(effects
				(font
					(size 1.27 1.27)
				)
			)
		)
		(duplicate_pad_numbers_are_jumpers no)
		(fp_line
			(start 0.7874 0.4064)
			(end -0.7874 0.4064)
			(stroke
				(width 0.1524)
				(type default)
			)
			(layer "F.SilkS")
		)
		(fp_line
			(start 0.7874 -0.4064)
			(end 0.7874 0.4064)
			(stroke
				(width 0.1524)
				(type default)
			)
			(layer "F.SilkS")
		)
		(fp_line
			(start -0.7874 0.4064)
			(end -0.7874 -0.4064)
			(stroke
				(width 0.1524)
				(type default)
			)
			(layer "F.SilkS")
		)
		(fp_line
			(start -0.7874 -0.4064)
			(end 0.7874 -0.4064)
			(stroke
				(width 0.1524)
				(type default)
			)
			(layer "F.SilkS")
		)
		(fp_line
			(start 0.67945 0.3048)
			(end 0.120396 0.3048)
			(stroke
				(width 0.1)
				(type default)
			)
			(layer "F.Fab")
		)
		(fp_line
			(start 0.67945 -0.3048)
			(end 0.67945 0.3048)
			(stroke
				(width 0.1)
				(type default)
			)
			(layer "F.Fab")
		)
		(fp_line
			(start 0.12065 -0.2794)
			(end 0.12065 -0.3048)
			(stroke
				(width 0.1)
				(type default)
			)
			(layer "F.Fab")
		)
		(fp_line
			(start 0.12065 -0.3048)
			(end 0.67945 -0.3048)
			(stroke
				(width 0.1)
				(type default)
			)
			(layer "F.Fab")
		)
		(fp_line
			(start 0.120396 0.3048)
			(end 0.120396 0.2794)
			(stroke
				(width 0.1)
				(type default)
			)
			(layer "F.Fab")
		)
		(fp_line
			(start 0.120396 0.2794)
			(end -0.12065 0.2794)
			(stroke
				(width 0.1)
				(type default)
			)
			(layer "F.Fab")
		)
		(fp_line
			(start -0.12065 0.3048)
			(end -0.67945 0.3048)
			(stroke
				(width 0.1)
				(type default)
			)
			(layer "F.Fab")
		)
		(fp_line
			(start -0.12065 0.2794)
			(end -0.12065 0.3048)
			(stroke
				(width 0.1)
				(type default)
			)
			(layer "F.Fab")
		)
		(fp_line
			(start -0.12065 -0.2794)
			(end 0.12065 -0.2794)
			(stroke
				(width 0.1)
				(type default)
			)
			(layer "F.Fab")
		)
		(fp_line
			(start -0.12065 -0.305054)
			(end -0.12065 -0.2794)
			(stroke
				(width 0.1)
				(type default)
			)
			(layer "F.Fab")
		)
		(fp_line
			(start -0.67945 0.3048)
			(end -0.67945 -0.305054)
			(stroke
				(width 0.1)
				(type default)
			)
			(layer "F.Fab")
		)
		(fp_line
			(start -0.67945 -0.305054)
			(end -0.12065 -0.305054)
			(stroke
				(width 0.1)
				(type default)
			)
			(layer "F.Fab")
		)
		(pad "1" smd rect
			(at -0.40005 0)
			(size 0.4572 0.508)
			(layers "F.Cu" "F.Mask" "F.Paste")
			(net "P12V_AUX_ADC")
		)
		(pad "2" smd rect
			(at 0.40005 0)
			(size 0.4572 0.508)
			(layers "F.Cu" "F.Mask" "F.Paste")
			(net "P12V_AUX_ADC_TIC")
		)
	)
	(footprint ""
		(layer "F.Cu")
		(at 50.95875 -440.187588)
		(property "Reference" "R2999"
			(at 0 0 0)
			(layer "F.SilkS")
			(hide yes)
			(effects
				(font
					(size 1.27 1.27)
				)
			)
		)
		(property "Value" ""
			(at 0 0 0)
			(layer "F.Fab")
			(effects
				(font
					(size 1.27 1.27)
				)
			)
		)
		(duplicate_pad_numbers_are_jumpers no)
		(fp_line
			(start -0.7874 -0.4064)
			(end 0.7874 -0.4064)
			(stroke
				(width 0.1524)
				(type default)
			)
			(layer "F.SilkS")
		)
		(fp_line
			(start -0.7874 0.4064)
			(end -0.7874 -0.4064)
			(stroke
				(width 0.1524)
				(type default)
			)
			(layer "F.SilkS")
		)
		(fp_line
			(start 0.7874 -0.4064)
			(end 0.7874 0.4064)
			(stroke
				(width 0.1524)
				(type default)
			)
			(layer "F.SilkS")
		)
		(fp_line
			(start 0.7874 0.4064)
			(end -0.7874 0.4064)
			(stroke
				(width 0.1524)
				(type default)
			)
			(layer "F.SilkS")
		)
		(fp_line
			(start -0.67945 -0.305054)
			(end -0.12065 -0.305054)
			(stroke
				(width 0.1)
				(type default)
			)
			(layer "F.Fab")
		)
		(fp_line
			(start -0.67945 0.3048)
			(end -0.67945 -0.305054)
			(stroke
				(width 0.1)
				(type default)
			)
			(layer "F.Fab")
		)
		(fp_line
			(start -0.12065 -0.305054)
			(end -0.12065 -0.2794)
			(stroke
				(width 0.1)
				(type default)
			)
			(layer "F.Fab")
		)
		(fp_line
			(start -0.12065 -0.2794)
			(end 0.12065 -0.2794)
			(stroke
				(width 0.1)
				(type default)
			)
			(layer "F.Fab")
		)
		(fp_line
			(start -0.12065 0.2794)
			(end -0.12065 0.3048)
			(stroke
				(width 0.1)
				(type default)
			)
			(layer "F.Fab")
		)
		(fp_line
			(start -0.12065 0.3048)
			(end -0.67945 0.3048)
			(stroke
				(width 0.1)
				(type default)
			)
			(layer "F.Fab")
		)
		(fp_line
			(start 0.120396 0.2794)
			(end -0.12065 0.2794)
			(stroke
				(width 0.1)
				(type default)
			)
			(layer "F.Fab")
		)
		(fp_line
			(start 0.120396 0.3048)
			(end 0.120396 0.2794)
			(stroke
				(width 0.1)
				(type default)
			)
			(layer "F.Fab")
		)
		(fp_line
			(start 0.12065 -0.3048)
			(end 0.67945 -0.3048)
			(stroke
				(width 0.1)
				(type default)
			)
			(layer "F.Fab")
		)
		(fp_line
			(start 0.12065 -0.2794)
			(end 0.12065 -0.3048)
			(stroke
				(width 0.1)
				(type default)
			)
			(layer "F.Fab")
		)
		(fp_line
			(start 0.67945 -0.3048)
			(end 0.67945 0.3048)
			(stroke
				(width 0.1)
				(type default)
			)
			(layer "F.Fab")
		)
		(fp_line
			(start 0.67945 0.3048)
			(end 0.120396 0.3048)
			(stroke
				(width 0.1)
				(type default)
			)
			(layer "F.Fab")
		)
		(pad "1" smd circle
			(at -0.40005 0)
			(size 0 0)
			(layers "F.Cu" "F.Mask" "F.Paste")
			(net "SMB_2_BMC_GPU_SCL")
		)
		(pad "2" smd circle
			(at 0.40005 0)
			(size 0 0)
			(layers "F.Cu" "F.Mask" "F.Paste")
			(net "P3V3_AUX")
		)
	)
	(footprint ""
		(layer "F.Cu")
		(at 87.382096 -70.78599)
		(property "Reference" "D89"
			(at -44.586906 50.178462 90)
			(unlocked yes)
			(layer "F.SilkS")
			(effects
				(font
					(size 0.635 0.4064)
					(thickness 0.1524)
				)
				(justify left)
			)
		)
		(property "Value" ""
			(at 0 0 0)
			(layer "F.Fab")
			(effects
				(font
					(size 1.27 1.27)
				)
			)
		)
		(duplicate_pad_numbers_are_jumpers no)
		(fp_line
			(start -0.90678 0.4826)
			(end -0.90678 -0.4699)
			(stroke
				(width 0.1524)
				(type default)
			)
			(layer "F.SilkS")
		)
		(fp_line
			(start -0.89408 -0.4826)
			(end 0.90678 -0.4826)
			(stroke
				(width 0.1524)
				(type default)
			)
			(layer "F.SilkS")
		)
		(fp_line
			(start -0.79248 -0.4826)
			(end 1.03378 -0.4826)
			(stroke
				(width 0.1524)
				(type default)
			)
			(layer "F.SilkS")
		)
		(fp_line
			(start -0.64008 -0.4826)
			(end 1.16078 -0.4826)
			(stroke
				(width 0.1524)
				(type default)
			)
			(layer "F.SilkS")
		)
		(fp_line
			(start 0.90678 -0.4826)
			(end 0.90678 0.4826)
			(stroke
				(width 0.1524)
				(type default)
			)
			(layer "F.SilkS")
		)
		(fp_line
			(start 0.90678 0.4826)
			(end -0.90678 0.4826)
			(stroke
				(width 0.1524)
				(type default)
			)
			(layer "F.SilkS")
		)
		(fp_line
			(start 1.03378 -0.4826)
			(end 1.03378 0.4826)
			(stroke
				(width 0.1524)
				(type default)
			)
			(layer "F.SilkS")
		)
		(fp_line
			(start 1.03378 0.4826)
			(end -0.79248 0.4826)
			(stroke
				(width 0.1524)
				(type default)
			)
			(layer "F.SilkS")
		)
		(fp_line
			(start 1.16078 -0.4826)
			(end 1.16078 0.4826)
			(stroke
				(width 0.1524)
				(type default)
			)
			(layer "F.SilkS")
		)
		(fp_line
			(start 1.16078 0.4826)
			(end -0.64008 0.4826)
			(stroke
				(width 0.1524)
				(type default)
			)
			(layer "F.SilkS")
		)
		(fp_line
			(start -0.499872 -0.249936)
			(end 0.499872 -0.249936)
			(stroke
				(width 0.1)
				(type default)
			)
			(layer "F.Fab")
		)
		(fp_line
			(start -0.499872 0.249936)
			(end -0.499872 -0.249936)
			(stroke
				(width 0.1)
				(type default)
			)
			(layer "F.Fab")
		)
		(fp_line
			(start 0.499872 -0.249936)
			(end 0.499872 0.249936)
			(stroke
				(width 0.1)
				(type default)
			)
			(layer "F.Fab")
		)
		(fp_line
			(start 0.499872 0.249936)
			(end -0.499872 0.249936)
			(stroke
				(width 0.1)
				(type default)
			)
			(layer "F.Fab")
		)
		(pad "A" smd rect
			(at -0.47498 0)
			(size 0.6096 0.7112)
			(layers "F.Cu" "F.Mask" "F.Paste")
			(net "LED_PWRGD_CPUPWRGD_GTL")
		)
		(pad "C" smd rect
			(at 0.47498 0)
			(size 0.6096 0.7112)
			(layers "F.Cu" "F.Mask" "F.Paste")
			(net "LED_PWRGD_CPUPWRGD_GTL_D")
		)
	)
	(footprint ""
		(layer "F.Cu")
		(at 107.2769 -256.6543 -90)
		(property "Reference" "C299"
			(at 0 0 270)
			(layer "F.SilkS")
			(hide yes)
			(effects
				(font
					(size 1.27 1.27)
				)
			)
		)
		(property "Value" ""
			(at 0 0 270)
			(layer "F.Fab")
			(effects
				(font
					(size 1.27 1.27)
				)
			)
		)
		(duplicate_pad_numbers_are_jumpers no)
		(fp_line
			(start -0.7874 0.4064)
			(end -0.7874 -0.4064)
			(stroke
				(width 0.1524)
				(type default)
			)
			(layer "F.SilkS")
		)
		(fp_line
			(start 0.7874 0.4064)
			(end -0.7874 0.4064)
			(stroke
				(width 0.1524)
				(type default)
			)
			(layer "F.SilkS")
		)
		(fp_line
			(start -0.7874 -0.4064)
			(end 0.7874 -0.4064)
			(stroke
				(width 0.1524)
				(type default)
			)
			(layer "F.SilkS")
		)
		(fp_line
			(start 0.7874 -0.4064)
			(end 0.7874 0.4064)
			(stroke
				(width 0.1524)
				(type default)
			)
			(layer "F.SilkS")
		)
		(fp_line
			(start -0.67945 0.3048)
			(end -0.67945 -0.305054)
			(stroke
				(width 0.1)
				(type default)
			)
			(layer "F.Fab")
		)
		(fp_line
			(start -0.12065 0.3048)
			(end -0.67945 0.3048)
			(stroke
				(width 0.1)
				(type default)
			)
			(layer "F.Fab")
		)
		(fp_line
			(start 0.120396 0.3048)
			(end 0.120396 0.2794)
			(stroke
				(width 0.1)
				(type default)
			)
			(layer "F.Fab")
		)
		(fp_line
			(start 0.67945 0.3048)
			(end 0.120396 0.3048)
			(stroke
				(width 0.1)
				(type default)
			)
			(layer "F.Fab")
		)
		(fp_line
			(start -0.12065 0.2794)
			(end -0.12065 0.3048)
			(stroke
				(width 0.1)
				(type default)
			)
			(layer "F.Fab")
		)
		(fp_line
			(start 0.120396 0.2794)
			(end -0.12065 0.2794)
			(stroke
				(width 0.1)
				(type default)
			)
			(layer "F.Fab")
		)
		(fp_line
			(start -0.12065 -0.2794)
			(end 0.12065 -0.2794)
			(stroke
				(width 0.1)
				(type default)
			)
			(layer "F.Fab")
		)
		(fp_line
			(start 0.12065 -0.2794)
			(end 0.12065 -0.3048)
			(stroke
				(width 0.1)
				(type default)
			)
			(layer "F.Fab")
		)
		(fp_line
			(start 0.12065 -0.3048)
			(end 0.67945 -0.3048)
			(stroke
				(width 0.1)
				(type default)
			)
			(layer "F.Fab")
		)
		(fp_line
			(start 0.67945 -0.3048)
			(end 0.67945 0.3048)
			(stroke
				(width 0.1)
				(type default)
			)
			(layer "F.Fab")
		)
		(fp_line
			(start -0.67945 -0.305054)
			(end -0.12065 -0.305054)
			(stroke
				(width 0.1)
				(type default)
			)
			(layer "F.Fab")
		)
		(fp_line
			(start -0.12065 -0.305054)
			(end -0.12065 -0.2794)
			(stroke
				(width 0.1)
				(type default)
			)
			(layer "F.Fab")
		)
		(pad "1" smd circle
			(at -0.40005 0 270)
			(size 0 0)
			(layers "F.Cu" "F.Mask" "F.Paste")
			(net "PVCCIN_CPU1")
		)
		(pad "2" smd circle
			(at 0.40005 0 270)
			(size 0 0)
			(layers "F.Cu" "F.Mask" "F.Paste")
			(net "GND")
		)
	)
)
